(kicad_pcb
	(version 20260206)
	(generator "pcbnew")
	(generator_version "10.0")
	(general
		(thickness 1.6)
		(legacy_teardrops no)
	)
	(paper "A4")
	(title_block
		(title "03242023_DA0F0TMBIJ0_F0T_Motherboard_J_brd_V01_OCP.brd")
		(comment 1 "Grand Teton / footprints 5176-5180 of 6105")
	)
	(layers
		(0 "F.Cu" signal "TOP")
		(4 "In1.Cu" signal "GND")
		(6 "In2.Cu" signal "IN1")
		(8 "In3.Cu" signal "GND1")
		(10 "In4.Cu" signal "IN2")
		(12 "In5.Cu" signal "GND2")
		(14 "In6.Cu" signal "IN3")
		(16 "In7.Cu" signal "GND3")
		(18 "In8.Cu" signal "VCC")
		(20 "In9.Cu" signal "VCC1")
		(22 "In10.Cu" signal "GND4")
		(24 "In11.Cu" signal "IN4")
		(26 "In12.Cu" signal "GND5")
		(28 "In13.Cu" signal "IN5")
		(30 "In14.Cu" signal "GND6")
		(32 "In15.Cu" signal "IN6")
		(34 "In16.Cu" signal "GND7")
		(2 "B.Cu" signal "BOTTOM")
		(9 "F.Adhes" user "F.Adhesive")
		(11 "B.Adhes" user "B.Adhesive")
		(13 "F.Paste" user "Package Geometry/Pastemask Top")
		(15 "B.Paste" user "Package Geometry/Pastemask Bottom")
		(5 "F.SilkS" user "Ref Des/Silkscreen Top")
		(7 "B.SilkS" user "Ref Des/Silkscreen Bottom")
		(1 "F.Mask" user "Board Geometry/Soldermask Top")
		(3 "B.Mask" user "Board Geometry/Soldermask Bottom")
		(17 "Dwgs.User" user "User.Drawings")
		(19 "Cmts.User" user "User.Comments")
		(21 "Eco1.User" user "User.Eco1")
		(23 "Eco2.User" user "User.Eco2")
		(25 "Edge.Cuts" user "Board Geometry/Outline")
		(27 "Margin" user)
		(31 "F.CrtYd" user "Package Geometry/Place Bound Top")
		(29 "B.CrtYd" user "Package Geometry/Place Bound Bottom")
		(35 "F.Fab" user "Ref Des/Assembly Top")
		(33 "B.Fab" user "Ref Des/Assembly Bottom")
	)
	(footprint ""
		(layer "B.Cu")
		(at 498.693948 -153.16454 90)
		(property "Reference" "X28"
			(at 1.46177 2.60096 270)
			(unlocked yes)
			(layer "B.SilkS")
			(effects
				(font
					(size 0.7874 0.5842)
					(thickness 0.1524)
				)
				(justify left mirror)
			)
		)
		(property "Value" ""
			(at 0 0 90)
			(layer "B.Fab")
			(effects
				(font
					(size 1.27 1.27)
				)
				(justify mirror)
			)
		)
		(property "Device Type" "TP_TDR_4P_FTS_TH-TP_TDR_4P_DIPA"
			(at -1.30175 1.27 0)
			(unlocked yes)
			(layer "B.Fab")
			(hide yes)
			(effects
				(font
					(size 0.635 0.4064)
					(thickness 0.1524)
				)
				(justify mirror)
			)
		)
		(property "User Part Number" "N_A"
			(at -1.30175 1.27 0)
			(unlocked yes)
			(layer "Cmts.User")
			(hide yes)
			(effects
				(font
					(size 0.635 0.4064)
					(thickness 0.1524)
				)
				(justify mirror)
			)
		)
		(duplicate_pad_numbers_are_jumpers no)
		(fp_line
			(start 0 -1.27)
			(end 0 -0.635)
			(stroke
				(width 0.1524)
				(type default)
			)
			(layer "B.SilkS")
		)
		(fp_line
			(start -2.54 -1.27)
			(end 0 -1.27)
			(stroke
				(width 0.1524)
				(type default)
			)
			(layer "B.SilkS")
		)
		(fp_line
			(start -2.54 -1.1303)
			(end -2.54 -1.27)
			(stroke
				(width 0.1524)
				(type default)
			)
			(layer "B.SilkS")
		)
		(fp_line
			(start 0 0.635)
			(end 0 1.905)
			(stroke
				(width 0.1524)
				(type default)
			)
			(layer "B.SilkS")
		)
		(fp_line
			(start -2.54 1.4097)
			(end -2.54 1.1303)
			(stroke
				(width 0.1524)
				(type default)
			)
			(layer "B.SilkS")
		)
		(fp_line
			(start 0 3.175)
			(end 0 3.81)
			(stroke
				(width 0.1524)
				(type default)
			)
			(layer "B.SilkS")
		)
		(fp_line
			(start 0 3.81)
			(end -2.54 3.81)
			(stroke
				(width 0.1524)
				(type default)
			)
			(layer "B.SilkS")
		)
		(fp_line
			(start -2.54 3.81)
			(end -2.54 3.6703)
			(stroke
				(width 0.1524)
				(type default)
			)
			(layer "B.SilkS")
		)
		(fp_poly
			(pts
				(xy 2.790952 -0.930402) (xy 2.790952 0.593598) (xy 1.266952 -0.168402)
			)
			(stroke
				(width 0)
				(type default)
			)
			(fill yes)
			(layer "B.SilkS")
		)
		(fp_line
			(start 0 -1.27)
			(end 0 3.81)
			(stroke
				(width 0.1)
				(type default)
			)
			(layer "B.Fab")
		)
		(fp_line
			(start -2.54 -1.27)
			(end 0 -1.27)
			(stroke
				(width 0.1)
				(type default)
			)
			(layer "B.Fab")
		)
		(fp_line
			(start 0 3.81)
			(end -2.54 3.81)
			(stroke
				(width 0.1)
				(type default)
			)
			(layer "B.Fab")
		)
		(fp_line
			(start -2.54 3.81)
			(end -2.54 -1.27)
			(stroke
				(width 0.1)
				(type default)
			)
			(layer "B.Fab")
		)
		(fp_poly
			(pts
				(xy 0.761746 0) (xy 2.285746 -0.762) (xy 2.285746 0.762)
			)
			(stroke
				(width 0)
				(type default)
			)
			(fill yes)
			(layer "B.Fab")
		)
		(pad "1" thru_hole circle
			(at 0 0 270)
			(size 1.0033 1.0033)
			(drill 0.249936)
			(layers "*.Cu" "*.Mask")
			(remove_unused_layers no)
			(net "TDR_DIFF_85_IN6_DN")
			(clearance 0.10795)
			(padstack
				(mode front_inner_back)
				(layer "Inner"
					(shape circle)
					(size 0.8001 0.8001)
					(clearance 0.1524)
				)
				(layer "B.Cu"
					(shape circle)
					(size 1.0033 1.0033)
					(thermal_gap 0.10795)
					(clearance 0.10795)
				)
			)
		)
		(pad "2" thru_hole circle
			(at -2.54 0 270)
			(size 1.9939 1.9939)
			(drill 0.249936)
			(layers "*.Cu" "*.Mask")
			(remove_unused_layers no)
			(net "T1_GND")
			(clearance 0.10795)
			(padstack
				(mode front_inner_back)
				(layer "Inner"
					(shape circle)
					(size 0.8001 0.8001)
					(clearance 0.1524)
				)
				(layer "B.Cu"
					(shape circle)
					(size 1.9939 1.9939)
					(thermal_gap 0.10795)
					(clearance 0.10795)
				)
			)
		)
		(pad "3" thru_hole circle
			(at -2.54 2.54 270)
			(size 1.9939 1.9939)
			(drill 0.249936)
			(layers "*.Cu" "*.Mask")
			(remove_unused_layers no)
			(net "T1_GND")
			(clearance 0.10795)
			(padstack
				(mode front_inner_back)
				(layer "Inner"
					(shape circle)
					(size 0.8001 0.8001)
					(clearance 0.1524)
				)
				(layer "B.Cu"
					(shape circle)
					(size 1.9939 1.9939)
					(thermal_gap 0.10795)
					(clearance 0.10795)
				)
			)
		)
		(pad "4" thru_hole circle
			(at 0 2.54 270)
			(size 1.0033 1.0033)
			(drill 0.249936)
			(layers "*.Cu" "*.Mask")
			(remove_unused_layers no)
			(net "TDR_DIFF_85_IN6_DP")
			(clearance 0.10795)
			(padstack
				(mode front_inner_back)
				(layer "Inner"
					(shape circle)
					(size 0.8001 0.8001)
					(clearance 0.1524)
				)
				(layer "B.Cu"
					(shape circle)
					(size 1.0033 1.0033)
					(thermal_gap 0.10795)
					(clearance 0.10795)
				)
			)
		)
	)
	(footprint ""
		(layer "B.Cu")
		(at 174.29988 -123.916948 90)
		(property "Reference" "R3348"
			(at 0 0 90)
			(layer "B.SilkS")
			(hide yes)
			(effects
				(font
					(size 1.27 1.27)
				)
				(justify mirror)
			)
		)
		(property "Value" ""
			(at 0 0 90)
			(layer "B.Fab")
			(effects
				(font
					(size 1.27 1.27)
				)
				(justify mirror)
			)
		)
		(duplicate_pad_numbers_are_jumpers no)
		(fp_line
			(start 1.2954 -0.5842)
			(end -1.2954 -0.5842)
			(stroke
				(width 0.1524)
				(type default)
			)
			(layer "B.SilkS")
		)
		(fp_line
			(start -1.2954 -0.5842)
			(end -1.2954 0.5842)
			(stroke
				(width 0.1524)
				(type default)
			)
			(layer "B.SilkS")
		)
		(fp_line
			(start 1.2954 0.5842)
			(end 1.2954 -0.5842)
			(stroke
				(width 0.1524)
				(type default)
			)
			(layer "B.SilkS")
		)
		(fp_line
			(start -1.2954 0.5842)
			(end 1.2954 0.5842)
			(stroke
				(width 0.1524)
				(type default)
			)
			(layer "B.SilkS")
		)
		(fp_line
			(start 0.8636 -0.4572)
			(end -0.8636 -0.4572)
			(stroke
				(width 0.1)
				(type default)
			)
			(layer "B.Fab")
		)
		(fp_line
			(start -0.8636 -0.4572)
			(end -0.8636 -0.406654)
			(stroke
				(width 0.1)
				(type default)
			)
			(layer "B.Fab")
		)
		(fp_line
			(start 1.1938 -0.406654)
			(end 0.8636 -0.406654)
			(stroke
				(width 0.1)
				(type default)
			)
			(layer "B.Fab")
		)
		(fp_line
			(start 0.8636 -0.406654)
			(end 0.8636 -0.4572)
			(stroke
				(width 0.1)
				(type default)
			)
			(layer "B.Fab")
		)
		(fp_line
			(start -0.8636 -0.406654)
			(end -1.1938 -0.406654)
			(stroke
				(width 0.1)
				(type default)
			)
			(layer "B.Fab")
		)
		(fp_line
			(start -1.1938 -0.406654)
			(end -1.1938 0.4064)
			(stroke
				(width 0.1)
				(type default)
			)
			(layer "B.Fab")
		)
		(fp_line
			(start 1.1938 0.4064)
			(end 1.1938 -0.406654)
			(stroke
				(width 0.1)
				(type default)
			)
			(layer "B.Fab")
		)
		(fp_line
			(start 0.8636 0.4064)
			(end 1.1938 0.4064)
			(stroke
				(width 0.1)
				(type default)
			)
			(layer "B.Fab")
		)
		(fp_line
			(start -0.8636 0.4064)
			(end -0.8636 0.4572)
			(stroke
				(width 0.1)
				(type default)
			)
			(layer "B.Fab")
		)
		(fp_line
			(start -1.1938 0.4064)
			(end -0.8636 0.4064)
			(stroke
				(width 0.1)
				(type default)
			)
			(layer "B.Fab")
		)
		(fp_line
			(start 0.8636 0.4318)
			(end 0.8636 0.4064)
			(stroke
				(width 0.1)
				(type default)
			)
			(layer "B.Fab")
		)
		(fp_line
			(start 0.8636 0.4572)
			(end 0.8636 0.4318)
			(stroke
				(width 0.1)
				(type default)
			)
			(layer "B.Fab")
		)
		(fp_line
			(start -0.8636 0.4572)
			(end 0.8636 0.4572)
			(stroke
				(width 0.1)
				(type default)
			)
			(layer "B.Fab")
		)
		(pad "1" smd rect
			(at 0.7366 0)
			(size 0.7112 0.8128)
			(layers "B.Cu" "B.Mask" "B.Paste")
			(net "P3V3_AUX")
		)
		(pad "2" smd rect
			(at -0.7366 0)
			(size 0.7112 0.8128)
			(layers "B.Cu" "B.Mask" "B.Paste")
			(net "P3V3_AUX_FPGA_VCCIO1")
		)
	)
	(footprint ""
		(layer "B.Cu")
		(at 211.632546 -319.268856 180)
		(property "Reference" "C75"
			(at 0 0 0)
			(layer "B.SilkS")
			(hide yes)
			(effects
				(font
					(size 1.27 1.27)
				)
				(justify mirror)
			)
		)
		(property "Value" ""
			(at 0 0 0)
			(layer "B.Fab")
			(effects
				(font
					(size 1.27 1.27)
				)
				(justify mirror)
			)
		)
		(duplicate_pad_numbers_are_jumpers no)
		(fp_line
			(start 0.7874 0.4064)
			(end 0.7874 -0.4064)
			(stroke
				(width 0.1524)
				(type default)
			)
			(layer "B.SilkS")
		)
		(fp_line
			(start 0.7874 -0.4064)
			(end -0.7874 -0.4064)
			(stroke
				(width 0.1524)
				(type default)
			)
			(layer "B.SilkS")
		)
		(fp_line
			(start -0.7874 0.4064)
			(end 0.7874 0.4064)
			(stroke
				(width 0.1524)
				(type default)
			)
			(layer "B.SilkS")
		)
		(fp_line
			(start -0.7874 -0.4064)
			(end -0.7874 0.4064)
			(stroke
				(width 0.1524)
				(type default)
			)
			(layer "B.SilkS")
		)
		(fp_line
			(start 0.67945 0.3048)
			(end 0.67945 -0.305054)
			(stroke
				(width 0.1)
				(type default)
			)
			(layer "B.Fab")
		)
		(fp_line
			(start 0.67945 -0.305054)
			(end 0.12065 -0.305054)
			(stroke
				(width 0.1)
				(type default)
			)
			(layer "B.Fab")
		)
		(fp_line
			(start 0.12065 0.3048)
			(end 0.67945 0.3048)
			(stroke
				(width 0.1)
				(type default)
			)
			(layer "B.Fab")
		)
		(fp_line
			(start 0.12065 0.2794)
			(end 0.12065 0.3048)
			(stroke
				(width 0.1)
				(type default)
			)
			(layer "B.Fab")
		)
		(fp_line
			(start 0.12065 -0.2794)
			(end -0.12065 -0.2794)
			(stroke
				(width 0.1)
				(type default)
			)
			(layer "B.Fab")
		)
		(fp_line
			(start 0.12065 -0.305054)
			(end 0.12065 -0.2794)
			(stroke
				(width 0.1)
				(type default)
			)
			(layer "B.Fab")
		)
		(fp_line
			(start -0.120396 0.3048)
			(end -0.120396 0.2794)
			(stroke
				(width 0.1)
				(type default)
			)
			(layer "B.Fab")
		)
		(fp_line
			(start -0.120396 0.2794)
			(end 0.12065 0.2794)
			(stroke
				(width 0.1)
				(type default)
			)
			(layer "B.Fab")
		)
		(fp_line
			(start -0.12065 -0.2794)
			(end -0.12065 -0.3048)
			(stroke
				(width 0.1)
				(type default)
			)
			(layer "B.Fab")
		)
		(fp_line
			(start -0.12065 -0.3048)
			(end -0.67945 -0.3048)
			(stroke
				(width 0.1)
				(type default)
			)
			(layer "B.Fab")
		)
		(fp_line
			(start -0.67945 0.3048)
			(end -0.120396 0.3048)
			(stroke
				(width 0.1)
				(type default)
			)
			(layer "B.Fab")
		)
		(fp_line
			(start -0.67945 -0.3048)
			(end -0.67945 0.3048)
			(stroke
				(width 0.1)
				(type default)
			)
			(layer "B.Fab")
		)
		(pad "1" smd circle
			(at 0.40005 0)
			(size 0 0)
			(layers "B.Cu" "B.Mask" "B.Paste")
			(net "P3V3_AUX")
		)
		(pad "2" smd circle
			(at -0.40005 0)
			(size 0 0)
			(layers "B.Cu" "B.Mask" "B.Paste")
			(net "GND")
		)
	)
	(footprint ""
		(layer "B.Cu")
		(at 357.368602 -356.50043 -90)
		(property "Reference" "PR4218"
			(at 0 0 90)
			(layer "B.SilkS")
			(hide yes)
			(effects
				(font
					(size 1.27 1.27)
				)
				(justify mirror)
			)
		)
		(property "Value" ""
			(at 0 0 90)
			(layer "B.Fab")
			(effects
				(font
					(size 1.27 1.27)
				)
				(justify mirror)
			)
		)
		(duplicate_pad_numbers_are_jumpers no)
		(fp_line
			(start -0.7874 0.4064)
			(end 0.7874 0.4064)
			(stroke
				(width 0.1524)
				(type default)
			)
			(layer "B.SilkS")
		)
		(fp_line
			(start 0.7874 0.4064)
			(end 0.7874 -0.4064)
			(stroke
				(width 0.1524)
				(type default)
			)
			(layer "B.SilkS")
		)
		(fp_line
			(start -0.7874 -0.4064)
			(end -0.7874 0.4064)
			(stroke
				(width 0.1524)
				(type default)
			)
			(layer "B.SilkS")
		)
		(fp_line
			(start 0.7874 -0.4064)
			(end -0.7874 -0.4064)
			(stroke
				(width 0.1524)
				(type default)
			)
			(layer "B.SilkS")
		)
		(fp_line
			(start -0.67945 0.3048)
			(end -0.120396 0.3048)
			(stroke
				(width 0.1)
				(type default)
			)
			(layer "B.Fab")
		)
		(fp_line
			(start -0.120396 0.3048)
			(end -0.120396 0.2794)
			(stroke
				(width 0.1)
				(type default)
			)
			(layer "B.Fab")
		)
		(fp_line
			(start 0.12065 0.3048)
			(end 0.67945 0.3048)
			(stroke
				(width 0.1)
				(type default)
			)
			(layer "B.Fab")
		)
		(fp_line
			(start 0.67945 0.3048)
			(end 0.67945 -0.305054)
			(stroke
				(width 0.1)
				(type default)
			)
			(layer "B.Fab")
		)
		(fp_line
			(start -0.120396 0.2794)
			(end 0.12065 0.2794)
			(stroke
				(width 0.1)
				(type default)
			)
			(layer "B.Fab")
		)
		(fp_line
			(start 0.12065 0.2794)
			(end 0.12065 0.3048)
			(stroke
				(width 0.1)
				(type default)
			)
			(layer "B.Fab")
		)
		(fp_line
			(start -0.12065 -0.2794)
			(end -0.12065 -0.3048)
			(stroke
				(width 0.1)
				(type default)
			)
			(layer "B.Fab")
		)
		(fp_line
			(start 0.12065 -0.2794)
			(end -0.12065 -0.2794)
			(stroke
				(width 0.1)
				(type default)
			)
			(layer "B.Fab")
		)
		(fp_line
			(start -0.67945 -0.3048)
			(end -0.67945 0.3048)
			(stroke
				(width 0.1)
				(type default)
			)
			(layer "B.Fab")
		)
		(fp_line
			(start -0.12065 -0.3048)
			(end -0.67945 -0.3048)
			(stroke
				(width 0.1)
				(type default)
			)
			(layer "B.Fab")
		)
		(fp_line
			(start 0.12065 -0.305054)
			(end 0.12065 -0.2794)
			(stroke
				(width 0.1)
				(type default)
			)
			(layer "B.Fab")
		)
		(fp_line
			(start 0.67945 -0.305054)
			(end 0.12065 -0.305054)
			(stroke
				(width 0.1)
				(type default)
			)
			(layer "B.Fab")
		)
		(pad "1" smd circle
			(at 0.40005 0 90)
			(size 0 0)
			(layers "B.Cu" "B.Mask" "B.Paste")
			(net "PVCCFA_EHV_FIVRA_CPU0_IMON3")
		)
		(pad "2" smd circle
			(at -0.40005 0 90)
			(size 0 0)
			(layers "B.Cu" "B.Mask" "B.Paste")
			(net "GND")
		)
	)
	(footprint ""
		(layer "B.Cu")
		(at 181.755542 -112.175544)
		(property "Reference" "C1142"
			(at 0 0 0)
			(layer "B.SilkS")
			(hide yes)
			(effects
				(font
					(size 1.27 1.27)
				)
				(justify mirror)
			)
		)
		(property "Value" ""
			(at 0 0 0)
			(layer "B.Fab")
			(effects
				(font
					(size 1.27 1.27)
				)
				(justify mirror)
			)
		)
		(duplicate_pad_numbers_are_jumpers no)
		(fp_line
			(start -0.69215 -0.2921)
			(end -0.69215 0.2921)
			(stroke
				(width 0.1524)
				(type default)
			)
			(layer "B.SilkS")
		)
		(fp_line
			(start -0.69215 0.2921)
			(end 0.69215 0.2921)
			(stroke
				(width 0.1524)
				(type default)
			)
			(layer "B.SilkS")
		)
		(fp_line
			(start 0.69215 -0.2921)
			(end -0.69215 -0.2921)
			(stroke
				(width 0.1524)
				(type default)
			)
			(layer "B.SilkS")
		)
		(fp_line
			(start 0.69215 0.2921)
			(end 0.69215 -0.2921)
			(stroke
				(width 0.1524)
				(type default)
			)
			(layer "B.SilkS")
		)
		(fp_line
			(start -0.51435 -0.2794)
			(end -0.51435 0.2794)
			(stroke
				(width 0.1)
				(type default)
			)
			(layer "B.Fab")
		)
		(fp_line
			(start -0.51435 0.2794)
			(end 0.51435 0.2794)
			(stroke
				(width 0.1)
				(type default)
			)
			(layer "B.Fab")
		)
		(fp_line
			(start 0.51435 -0.2794)
			(end -0.51435 -0.2794)
			(stroke
				(width 0.1)
				(type default)
			)
			(layer "B.Fab")
		)
		(fp_line
			(start 0.51435 0.2794)
			(end 0.51435 -0.2794)
			(stroke
				(width 0.1)
				(type default)
			)
			(layer "B.Fab")
		)
		(pad "1" smd circle
			(at 0.40005 0 180)
			(size 0 0)
			(layers "B.Cu" "B.Mask" "B.Paste")
			(net "P3V3_AUX_FPGA_VCCIO2")
		)
		(pad "2" smd circle
			(at -0.40005 0 180)
			(size 0 0)
			(layers "B.Cu" "B.Mask" "B.Paste")
			(net "GND")
		)
		(zone
			(layer "B.Cu")
			(hatch none 0.5)
			(connect_pads
				(clearance 0)
			)
			(min_thickness 0.25)
			(keepout
				(tracks not_allowed)
				(vias allowed)
				(pads allowed)
				(copperpour not_allowed)
				(footprints allowed)
			)
			(placement
				(enabled no)
				(sheetname "")
			)
			(fill
				(thermal_gap 0.5)
				(thermal_bridge_width 0.5)
				(island_removal_mode 0)
			)
			(polygon
				(pts
					(xy 181.946042 -112.087914) (xy 181.854602 -112.029748) (xy 181.655212 -112.029748) (xy 181.565042 -112.087914)
					(xy 181.565042 -112.263174) (xy 181.655212 -112.321594) (xy 181.854602 -112.321594) (xy 181.946042 -112.263428)
				)
			)
		)
	)
)
